(kicad_pcb
	(version 20260206)
	(generator "pcbnew")
	(generator_version "10.0")
	(general
		(thickness 1.6)
		(legacy_teardrops no)
	)
	(paper "A4")
	(title_block
		(title "Wiwynn_Tioga_Pass_MB.brd")
		(comment 1 "Tioga Pass / footprint 949 of 4770 (J8G1), pads 1-113 of 204")
	)
	(layers
		(0 "F.Cu" signal "TOP")
		(4 "In1.Cu" signal "L2GND")
		(6 "In2.Cu" signal "L3")
		(8 "In3.Cu" signal "L4GND")
		(10 "In4.Cu" signal "L5")
		(12 "In5.Cu" signal "L6GND")
		(14 "In6.Cu" signal "L7VCC")
		(16 "In7.Cu" signal "L8VCC")
		(18 "In8.Cu" signal "L9GND")
		(20 "In9.Cu" signal "L10")
		(22 "In10.Cu" signal "L11GND")
		(24 "In11.Cu" signal "L12")
		(26 "In12.Cu" signal "L13GND")
		(2 "B.Cu" signal "BOTTOM")
		(9 "F.Adhes" user "F.Adhesive")
		(11 "B.Adhes" user "B.Adhesive")
		(13 "F.Paste" user "Package Geometry/Pastemask Top")
		(15 "B.Paste" user "Package Geometry/Pastemask Bottom")
		(5 "F.SilkS" user "Ref Des/Silkscreen Top")
		(7 "B.SilkS" user "Ref Des/Silkscreen Bottom")
		(1 "F.Mask" user "Board Geometry/Soldermask Top")
		(3 "B.Mask" user "Board Geometry/Soldermask Bottom")
		(17 "Dwgs.User" user "User.Drawings")
		(19 "Cmts.User" user "User.Comments")
		(21 "Eco1.User" user "User.Eco1")
		(23 "Eco2.User" user "User.Eco2")
		(25 "Edge.Cuts" user "Board Geometry/Outline")
		(27 "Margin" user)
		(31 "F.CrtYd" user "Package Geometry/Place Bound Top")
		(29 "B.CrtYd" user "Package Geometry/Place Bound Bottom")
		(35 "F.Fab" user "Ref Des/Assembly Top")
		(33 "B.Fab" user "Ref Des/Assembly Bottom")
	)
	(footprint ""
		(layer "F.Cu")
		(at 474.080078 -7.789672 -90)
		(property "Reference" "J8G1"
			(at -3.126486 25.39111 0)
			(unlocked yes)
			(layer "F.SilkS")
			(effects
				(font
					(size 0.7874 0.5842)
					(thickness 0.1524)
				)
				(justify left)
			)
		)
		(property "Value" ""
			(at 0 0 270)
			(layer "F.Fab")
			(effects
				(font
					(size 1.27 1.27)
				)
			)
		)
		(duplicate_pad_numbers_are_jumpers no)
		(pad "" np_thru_hole circle
			(at 0.201676 -1.495044 270)
			(size 0.254 0.254)
			(drill 1.27)
			(layers "*.Cu" "*.Mask")
			(clearance 0.8255)
			(thermal_gap 0.8255)
		)
		(pad "" np_thru_hole circle
			(at 1.7018 83.904836 270)
			(size 0.254 0.254)
			(drill 1.27)
			(layers "*.Cu" "*.Mask")
			(clearance 0.8255)
			(thermal_gap 0.8255)
		)
		(pad "1" smd rect
			(at 0 0 270)
			(size 1.1938 0.508)
			(layers "F.Cu" "F.Mask" "F.Paste")
			(net "P12V")
		)
		(pad "2" smd rect
			(at 3.4036 0 270)
			(size 1.1938 0.508)
			(layers "F.Cu" "F.Mask" "F.Paste")
			(net "P12V")
		)
		(pad "3" smd rect
			(at 0 0.8001 270)
			(size 1.1938 0.508)
			(layers "F.Cu" "F.Mask" "F.Paste")
			(net "P12V")
		)
		(pad "4" smd rect
			(at 3.4036 0.8001 270)
			(size 1.1938 0.508)
			(layers "F.Cu" "F.Mask" "F.Paste")
			(net "P12V")
		)
		(pad "5" smd rect
			(at 0 1.6002 270)
			(size 1.1938 0.508)
			(layers "F.Cu" "F.Mask" "F.Paste")
			(net "P12V")
		)
		(pad "6" smd rect
			(at 3.4036 1.6002 270)
			(size 1.1938 0.508)
			(layers "F.Cu" "F.Mask" "F.Paste")
			(net "P12V")
		)
		(pad "7" smd rect
			(at 0 2.4003 270)
			(size 1.1938 0.508)
			(layers "F.Cu" "F.Mask" "F.Paste")
			(net "P12V")
		)
		(pad "8" smd rect
			(at 3.4036 2.4003 270)
			(size 1.1938 0.508)
			(layers "F.Cu" "F.Mask" "F.Paste")
			(net "P12V")
		)
		(pad "9" smd rect
			(at 0 3.2004 270)
			(size 1.1938 0.508)
			(layers "F.Cu" "F.Mask" "F.Paste")
			(net "P12V")
		)
		(pad "10" smd rect
			(at 3.4036 3.2004 270)
			(size 1.1938 0.508)
			(layers "F.Cu" "F.Mask" "F.Paste")
			(net "P12V")
		)
		(pad "11" smd rect
			(at 0 4.0005 270)
			(size 1.1938 0.508)
			(layers "F.Cu" "F.Mask" "F.Paste")
			(net "P12V")
		)
		(pad "12" smd rect
			(at 3.4036 4.0005 270)
			(size 1.1938 0.508)
			(layers "F.Cu" "F.Mask" "F.Paste")
			(net "P12V")
		)
		(pad "13" smd rect
			(at 0 4.8006 270)
			(size 1.1938 0.508)
			(layers "F.Cu" "F.Mask" "F.Paste")
			(net "GND")
		)
		(pad "14" smd rect
			(at 3.4036 4.8006 270)
			(size 1.1938 0.508)
			(layers "F.Cu" "F.Mask" "F.Paste")
			(net "GND")
		)
		(pad "15" smd rect
			(at 0 5.6007 270)
			(size 1.1938 0.508)
			(layers "F.Cu" "F.Mask" "F.Paste")
			(net "SMB_SLOTX24_STBY_LVC3_SDA_R2")
		)
		(pad "16" smd rect
			(at 3.4036 5.6007 270)
			(size 1.1938 0.508)
			(layers "F.Cu" "F.Mask" "F.Paste")
			(net "IRQ_OOB_MGMT_RISER_ALERT_N")
		)
		(pad "17" smd rect
			(at 0 6.4008 270)
			(size 1.1938 0.508)
			(layers "F.Cu" "F.Mask" "F.Paste")
			(net "SMB_SLOTX24_STBY_LVC3_SCL_R2")
		)
		(pad "18" smd rect
			(at 3.4036 6.4008 270)
			(size 1.1938 0.508)
			(layers "F.Cu" "F.Mask" "F.Paste")
			(net "FM_SLT_CFG1")
		)
		(pad "19" smd rect
			(at 0 7.2009 270)
			(size 1.1938 0.508)
			(layers "F.Cu" "F.Mask" "F.Paste")
			(net "FM_SLT_CFG0")
		)
		(pad "20" smd rect
			(at 3.4036 7.2009 270)
			(size 1.1938 0.508)
			(layers "F.Cu" "F.Mask" "F.Paste")
			(net "FM_PWRBRK_SLOT_N")
		)
		(pad "21" smd rect
			(at 0 8.001 270)
			(size 1.1938 0.508)
			(layers "F.Cu" "F.Mask" "F.Paste")
			(net "P3V3")
		)
		(pad "22" smd rect
			(at 3.4036 8.001 270)
			(size 1.1938 0.508)
			(layers "F.Cu" "F.Mask" "F.Paste")
			(net "P3V3")
		)
		(pad "23" smd rect
			(at 0 8.8011 270)
			(size 1.1938 0.508)
			(layers "F.Cu" "F.Mask" "F.Paste")
			(net "P3V3")
		)
		(pad "24" smd rect
			(at 3.4036 8.8011 270)
			(size 1.1938 0.508)
			(layers "F.Cu" "F.Mask" "F.Paste")
			(net "P3V3")
		)
		(pad "25" smd rect
			(at 0 9.6012 270)
			(size 1.1938 0.508)
			(layers "F.Cu" "F.Mask" "F.Paste")
			(net "P3V3_STBY")
		)
		(pad "26" smd rect
			(at 3.4036 9.6012 270)
			(size 1.1938 0.508)
			(layers "F.Cu" "F.Mask" "F.Paste")
			(net "GND")
		)
		(pad "27" smd rect
			(at 0 10.4013 270)
			(size 1.1938 0.508)
			(layers "F.Cu" "F.Mask" "F.Paste")
			(net "PU_PCH_TLS_ENABLE_STRAP")
		)
		(pad "28" smd rect
			(at 3.4036 10.4013 270)
			(size 1.1938 0.508)
			(layers "F.Cu" "F.Mask" "F.Paste")
			(net "FM_PE_SLOTX24_WAKE_N")
		)
		(pad "29" smd rect
			(at 0 11.2014 270)
			(size 1.1938 0.508)
			(layers "F.Cu" "F.Mask" "F.Paste")
			(net "RST_PCIE_RISER1_PERST_R_N")
		)
		(pad "30" smd rect
			(at 3.4036 11.2014 270)
			(size 1.1938 0.508)
			(layers "F.Cu" "F.Mask" "F.Paste")
			(net "SMB_HOST_STBY_LVC3_SDA_R5")
		)
		(pad "31" smd rect
			(at 0 12.0015 270)
			(size 1.1938 0.508)
			(layers "F.Cu" "F.Mask" "F.Paste")
			(net "GND")
		)
		(pad "32" smd rect
			(at 3.4036 12.0015 270)
			(size 1.1938 0.508)
			(layers "F.Cu" "F.Mask" "F.Paste")
			(net "SMB_HOST_STBY_LVC3_SCL_R5")
		)
		(pad "33" smd rect
			(at 0 12.8016 270)
			(size 1.1938 0.508)
			(layers "F.Cu" "F.Mask" "F.Paste")
			(net "CLK_100M_PCH_SLOTX24_S5_DP")
		)
		(pad "34" smd rect
			(at 3.4036 12.8016 270)
			(size 1.1938 0.508)
			(layers "F.Cu" "F.Mask" "F.Paste")
			(net "GND")
		)
		(pad "35" smd rect
			(at 0 13.6017 270)
			(size 1.1938 0.508)
			(layers "F.Cu" "F.Mask" "F.Paste")
			(net "CLK_100M_PCH_SLOTX24_S5_DN")
		)
		(pad "36" smd rect
			(at 3.4036 13.6017 270)
			(size 1.1938 0.508)
			(layers "F.Cu" "F.Mask" "F.Paste")
			(net "CLK_100M_PCH_SLOTX24_S4_DP")
		)
		(pad "37" smd rect
			(at 0 14.4018 270)
			(size 1.1938 0.508)
			(layers "F.Cu" "F.Mask" "F.Paste")
			(net "GND")
		)
		(pad "38" smd rect
			(at 3.4036 14.4018 270)
			(size 1.1938 0.508)
			(layers "F.Cu" "F.Mask" "F.Paste")
			(net "CLK_100M_PCH_SLOTX24_S4_DN")
		)
		(pad "39" smd rect
			(at 0 15.2019 270)
			(size 1.1938 0.508)
			(layers "F.Cu" "F.Mask" "F.Paste")
			(net "CLK_100M_PCH_SLOTX24_S0_DP")
		)
		(pad "40" smd rect
			(at 3.4036 15.2019 270)
			(size 1.1938 0.508)
			(layers "F.Cu" "F.Mask" "F.Paste")
			(net "GND")
		)
		(pad "41" smd rect
			(at 0 16.002 270)
			(size 1.1938 0.508)
			(layers "F.Cu" "F.Mask" "F.Paste")
			(net "CLK_100M_PCH_SLOTX24_S0_DN")
		)
		(pad "42" smd rect
			(at 3.4036 16.002 270)
			(size 1.1938 0.508)
			(layers "F.Cu" "F.Mask" "F.Paste")
			(net "CLK_100M_PCH_SLOTX24_S1_DP")
		)
		(pad "43" smd rect
			(at 0 16.8021 270)
			(size 1.1938 0.508)
			(layers "F.Cu" "F.Mask" "F.Paste")
			(net "GND")
		)
		(pad "44" smd rect
			(at 3.4036 16.8021 270)
			(size 1.1938 0.508)
			(layers "F.Cu" "F.Mask" "F.Paste")
			(net "CLK_100M_PCH_SLOTX24_S1_DN")
		)
		(pad "45" smd rect
			(at 0 17.6022 270)
			(size 1.1938 0.508)
			(layers "F.Cu" "F.Mask" "F.Paste")
			(net "CLK_100M_PCH_SLOTX24_S3_DP")
		)
		(pad "46" smd rect
			(at 3.4036 17.6022 270)
			(size 1.1938 0.508)
			(layers "F.Cu" "F.Mask" "F.Paste")
			(net "GND")
		)
		(pad "47" smd rect
			(at 0 18.4023 270)
			(size 1.1938 0.508)
			(layers "F.Cu" "F.Mask" "F.Paste")
			(net "CLK_100M_PCH_SLOTX24_S3_DN")
		)
		(pad "48" smd rect
			(at 3.4036 18.4023 270)
			(size 1.1938 0.508)
			(layers "F.Cu" "F.Mask" "F.Paste")
			(net "CLK_100M_PCH_SLOTX24_S2_DP")
		)
		(pad "49" smd rect
			(at 0 19.2024 270)
			(size 1.1938 0.508)
			(layers "F.Cu" "F.Mask" "F.Paste")
			(net "GND")
		)
		(pad "50" smd rect
			(at 3.4036 19.2024 270)
			(size 1.1938 0.508)
			(layers "F.Cu" "F.Mask" "F.Paste")
			(net "CLK_100M_PCH_SLOTX24_S2_DN")
		)
		(pad "51" smd rect
			(at 0 20.0025 270)
			(size 1.1938 0.508)
			(layers "F.Cu" "F.Mask" "F.Paste")
			(net "P3E_CPU0_PE1_PCH_CON_TXN<15>")
		)
		(pad "52" smd rect
			(at 3.4036 20.0025 270)
			(size 1.1938 0.508)
			(layers "F.Cu" "F.Mask" "F.Paste")
			(net "GND")
		)
		(pad "53" smd rect
			(at 0 20.8026 270)
			(size 1.1938 0.508)
			(layers "F.Cu" "F.Mask" "F.Paste")
			(net "P3E_CPU0_PE1_PCH_CON_TXP<15>")
		)
		(pad "54" smd rect
			(at 3.4036 20.8026 270)
			(size 1.1938 0.508)
			(layers "F.Cu" "F.Mask" "F.Paste")
			(net "P3E_CPU0_PE1_PCH_CON_RXN<15>")
		)
		(pad "55" smd rect
			(at 0 21.6027 270)
			(size 1.1938 0.508)
			(layers "F.Cu" "F.Mask" "F.Paste")
			(net "GND")
		)
		(pad "56" smd rect
			(at 3.4036 21.6027 270)
			(size 1.1938 0.508)
			(layers "F.Cu" "F.Mask" "F.Paste")
			(net "P3E_CPU0_PE1_PCH_CON_RXP<15>")
		)
		(pad "57" smd rect
			(at 0 22.4028 270)
			(size 1.1938 0.508)
			(layers "F.Cu" "F.Mask" "F.Paste")
			(net "P3E_CPU0_PE1_PCH_CON_TXP<14>")
		)
		(pad "58" smd rect
			(at 3.4036 22.4028 270)
			(size 1.1938 0.508)
			(layers "F.Cu" "F.Mask" "F.Paste")
			(net "GND")
		)
		(pad "59" smd rect
			(at 0 23.2029 270)
			(size 1.1938 0.508)
			(layers "F.Cu" "F.Mask" "F.Paste")
			(net "P3E_CPU0_PE1_PCH_CON_TXN<14>")
		)
		(pad "60" smd rect
			(at 3.4036 23.2029 270)
			(size 1.1938 0.508)
			(layers "F.Cu" "F.Mask" "F.Paste")
			(net "P3E_CPU0_PE1_PCH_CON_RXN<14>")
		)
		(pad "61" smd rect
			(at 0 24.003 270)
			(size 1.1938 0.508)
			(layers "F.Cu" "F.Mask" "F.Paste")
			(net "GND")
		)
		(pad "62" smd rect
			(at 3.4036 24.003 270)
			(size 1.1938 0.508)
			(layers "F.Cu" "F.Mask" "F.Paste")
			(net "P3E_CPU0_PE1_PCH_CON_RXP<14>")
		)
		(pad "63" smd rect
			(at 0 24.8031 270)
			(size 1.1938 0.508)
			(layers "F.Cu" "F.Mask" "F.Paste")
			(net "TP_SLOTX24_RSVD63")
		)
		(pad "64" smd rect
			(at 3.4036 24.8031 270)
			(size 1.1938 0.508)
			(layers "F.Cu" "F.Mask" "F.Paste")
			(net "GND")
		)
		(pad "65" smd rect
			(at 0 28.803092 270)
			(size 1.1938 0.508)
			(layers "F.Cu" "F.Mask" "F.Paste")
			(net "GND")
		)
		(pad "66" smd rect
			(at 3.4036 28.803092 270)
			(size 1.1938 0.508)
			(layers "F.Cu" "F.Mask" "F.Paste")
			(net "TP_SLOTX24_RSVD66")
		)
		(pad "67" smd rect
			(at 0 29.603192 270)
			(size 1.1938 0.508)
			(layers "F.Cu" "F.Mask" "F.Paste")
			(net "P3E_CPU0_PE1_PCH_CON_TXN<13>")
		)
		(pad "68" smd rect
			(at 3.4036 29.603192 270)
			(size 1.1938 0.508)
			(layers "F.Cu" "F.Mask" "F.Paste")
			(net "GND")
		)
		(pad "69" smd rect
			(at 0 30.403292 270)
			(size 1.1938 0.508)
			(layers "F.Cu" "F.Mask" "F.Paste")
			(net "P3E_CPU0_PE1_PCH_CON_TXP<13>")
		)
		(pad "70" smd rect
			(at 3.4036 30.403292 270)
			(size 1.1938 0.508)
			(layers "F.Cu" "F.Mask" "F.Paste")
			(net "P3E_CPU0_PE1_PCH_CON_RXN<13>")
		)
		(pad "71" smd rect
			(at 0 31.203392 270)
			(size 1.1938 0.508)
			(layers "F.Cu" "F.Mask" "F.Paste")
			(net "GND")
		)
		(pad "72" smd rect
			(at 3.4036 31.203392 270)
			(size 1.1938 0.508)
			(layers "F.Cu" "F.Mask" "F.Paste")
			(net "P3E_CPU0_PE1_PCH_CON_RXP<13>")
		)
		(pad "73" smd rect
			(at 0 32.003492 270)
			(size 1.1938 0.508)
			(layers "F.Cu" "F.Mask" "F.Paste")
			(net "P3E_CPU0_PE1_PCH_CON_TXN<12>")
		)
		(pad "74" smd rect
			(at 3.4036 32.003492 270)
			(size 1.1938 0.508)
			(layers "F.Cu" "F.Mask" "F.Paste")
			(net "GND")
		)
		(pad "75" smd rect
			(at 0 32.803592 270)
			(size 1.1938 0.508)
			(layers "F.Cu" "F.Mask" "F.Paste")
			(net "P3E_CPU0_PE1_PCH_CON_TXP<12>")
		)
		(pad "76" smd rect
			(at 3.4036 32.803592 270)
			(size 1.1938 0.508)
			(layers "F.Cu" "F.Mask" "F.Paste")
			(net "P3E_CPU0_PE1_PCH_CON_RXN<12>")
		)
		(pad "77" smd rect
			(at 0 33.603692 270)
			(size 1.1938 0.508)
			(layers "F.Cu" "F.Mask" "F.Paste")
			(net "GND")
		)
		(pad "78" smd rect
			(at 3.4036 33.603692 270)
			(size 1.1938 0.508)
			(layers "F.Cu" "F.Mask" "F.Paste")
			(net "P3E_CPU0_PE1_PCH_CON_RXP<12>")
		)
		(pad "79" smd rect
			(at 0 34.403792 270)
			(size 1.1938 0.508)
			(layers "F.Cu" "F.Mask" "F.Paste")
			(net "P3E_CPU0_PE1_PCH_CON_TXN<11>")
		)
		(pad "80" smd rect
			(at 3.4036 34.403792 270)
			(size 1.1938 0.508)
			(layers "F.Cu" "F.Mask" "F.Paste")
			(net "GND")
		)
		(pad "81" smd rect
			(at 0 35.203892 270)
			(size 1.1938 0.508)
			(layers "F.Cu" "F.Mask" "F.Paste")
			(net "P3E_CPU0_PE1_PCH_CON_TXP<11>")
		)
		(pad "82" smd rect
			(at 3.4036 35.203892 270)
			(size 1.1938 0.508)
			(layers "F.Cu" "F.Mask" "F.Paste")
			(net "P3E_CPU0_PE1_PCH_CON_RXN<11>")
		)
		(pad "83" smd rect
			(at 0 36.003992 270)
			(size 1.1938 0.508)
			(layers "F.Cu" "F.Mask" "F.Paste")
			(net "GND")
		)
		(pad "84" smd rect
			(at 3.4036 36.003992 270)
			(size 1.1938 0.508)
			(layers "F.Cu" "F.Mask" "F.Paste")
			(net "P3E_CPU0_PE1_PCH_CON_RXP<11>")
		)
		(pad "85" smd rect
			(at 0 36.804092 270)
			(size 1.1938 0.508)
			(layers "F.Cu" "F.Mask" "F.Paste")
			(net "P3E_CPU0_PE1_PCH_CON_TXN<10>")
		)
		(pad "86" smd rect
			(at 3.4036 36.804092 270)
			(size 1.1938 0.508)
			(layers "F.Cu" "F.Mask" "F.Paste")
			(net "GND")
		)
		(pad "87" smd rect
			(at 0 37.604192 270)
			(size 1.1938 0.508)
			(layers "F.Cu" "F.Mask" "F.Paste")
			(net "P3E_CPU0_PE1_PCH_CON_TXP<10>")
		)
		(pad "88" smd rect
			(at 3.4036 37.604192 270)
			(size 1.1938 0.508)
			(layers "F.Cu" "F.Mask" "F.Paste")
			(net "P3E_CPU0_PE1_PCH_CON_RXN<10>")
		)
		(pad "89" smd rect
			(at 0 38.404292 270)
			(size 1.1938 0.508)
			(layers "F.Cu" "F.Mask" "F.Paste")
			(net "GND")
		)
		(pad "90" smd rect
			(at 3.4036 38.404292 270)
			(size 1.1938 0.508)
			(layers "F.Cu" "F.Mask" "F.Paste")
			(net "P3E_CPU0_PE1_PCH_CON_RXP<10>")
		)
		(pad "91" smd rect
			(at 0 39.204392 270)
			(size 1.1938 0.508)
			(layers "F.Cu" "F.Mask" "F.Paste")
			(net "P3E_CPU0_PE1_PCH_CON_TXN<9>")
		)
		(pad "92" smd rect
			(at 3.4036 39.204392 270)
			(size 1.1938 0.508)
			(layers "F.Cu" "F.Mask" "F.Paste")
			(net "GND")
		)
		(pad "93" smd rect
			(at 0 40.004492 270)
			(size 1.1938 0.508)
			(layers "F.Cu" "F.Mask" "F.Paste")
			(net "P3E_CPU0_PE1_PCH_CON_TXP<9>")
		)
		(pad "94" smd rect
			(at 3.4036 40.004492 270)
			(size 1.1938 0.508)
			(layers "F.Cu" "F.Mask" "F.Paste")
			(net "P3E_CPU0_PE1_PCH_CON_RXN<9>")
		)
		(pad "95" smd rect
			(at 0 40.804592 270)
			(size 1.1938 0.508)
			(layers "F.Cu" "F.Mask" "F.Paste")
			(net "GND")
		)
		(pad "96" smd rect
			(at 3.4036 40.804592 270)
			(size 1.1938 0.508)
			(layers "F.Cu" "F.Mask" "F.Paste")
			(net "P3E_CPU0_PE1_PCH_CON_RXP<9>")
		)
		(pad "97" smd rect
			(at 0 41.604692 270)
			(size 1.1938 0.508)
			(layers "F.Cu" "F.Mask" "F.Paste")
			(net "P3E_CPU0_PE1_PCH_CON_TXN<8>")
		)
		(pad "98" smd rect
			(at 3.4036 41.604692 270)
			(size 1.1938 0.508)
			(layers "F.Cu" "F.Mask" "F.Paste")
			(net "GND")
		)
		(pad "99" smd rect
			(at 0 42.404792 270)
			(size 1.1938 0.508)
			(layers "F.Cu" "F.Mask" "F.Paste")
			(net "P3E_CPU0_PE1_PCH_CON_TXP<8>")
		)
		(pad "100" smd rect
			(at 3.4036 42.404792 270)
			(size 1.1938 0.508)
			(layers "F.Cu" "F.Mask" "F.Paste")
			(net "P3E_CPU0_PE1_PCH_CON_RXN<8>")
		)
		(pad "101" smd rect
			(at 0 43.204892 270)
			(size 1.1938 0.508)
			(layers "F.Cu" "F.Mask" "F.Paste")
			(net "GND")
		)
		(pad "102" smd rect
			(at 3.4036 43.204892 270)
			(size 1.1938 0.508)
			(layers "F.Cu" "F.Mask" "F.Paste")
			(net "P3E_CPU0_PE1_PCH_CON_RXP<8>")
		)
		(pad "103" smd rect
			(at 0 44.004992 270)
			(size 1.1938 0.508)
			(layers "F.Cu" "F.Mask" "F.Paste")
			(net "P3E_CPU0_PE1_SS_C_TXP<7>")
		)
		(pad "104" smd rect
			(at 3.4036 44.004992 270)
			(size 1.1938 0.508)
			(layers "F.Cu" "F.Mask" "F.Paste")
			(net "GND")
		)
		(pad "105" smd rect
			(at 0 44.805092 270)
			(size 1.1938 0.508)
			(layers "F.Cu" "F.Mask" "F.Paste")
			(net "P3E_CPU0_PE1_SS_C_TXN<7>")
		)
		(pad "106" smd rect
			(at 3.4036 44.805092 270)
			(size 1.1938 0.508)
			(layers "F.Cu" "F.Mask" "F.Paste")
			(net "P3E_CPU0_PE1_SS_R_RXN<7>")
		)
		(pad "107" smd rect
			(at 0 45.605192 270)
			(size 1.1938 0.508)
			(layers "F.Cu" "F.Mask" "F.Paste")
			(net "GND")
		)
		(pad "108" smd rect
			(at 3.4036 45.605192 270)
			(size 1.1938 0.508)
			(layers "F.Cu" "F.Mask" "F.Paste")
			(net "P3E_CPU0_PE1_SS_R_RXP<7>")
		)
		(pad "109" smd rect
			(at 0 46.405292 270)
			(size 1.1938 0.508)
			(layers "F.Cu" "F.Mask" "F.Paste")
			(net "P3E_CPU0_PE1_SS_C_TXN<6>")
		)
		(pad "110" smd rect
			(at 3.4036 46.405292 270)
			(size 1.1938 0.508)
			(layers "F.Cu" "F.Mask" "F.Paste")
			(net "GND")
		)
		(pad "111" smd rect
			(at 0 47.205392 270)
			(size 1.1938 0.508)
			(layers "F.Cu" "F.Mask" "F.Paste")
			(net "P3E_CPU0_PE1_SS_C_TXP<6>")
		)
	)
)
